# T6G (Grand Teton) — schematic netlist excerpt (pin names and nets, part order shuffled) for the footprints in the layout excerpt that follows; sources: Cadence DE-HDL packaged netlist, KiCad conversion of 04192023_DAF0TMB3IC0_F0TG_MB_C_brd_V02_OCP.brd

C436  Q_CAP  10UF 6.3V 20% X6S  pkg C0402  page 356 : A = P1V8_CPU1_RT_1D ; B = GND
C2240  Q_CAP  22UF 4V 20% X6S  pkg C0402  page 69 : A = PVDDCR_CPU1_P0 ; B = GND

(kicad_pcb
	(version 20260206)
	(generator "pcbnew")
	(generator_version "10.0")
	(general
		(thickness 1.6)
		(legacy_teardrops no)
	)
	(paper "A4")
	(title_block
		(title "04192023_DAF0TMB3IC0_F0TG_MB_C_brd_V02_OCP.brd")
		(comment 1 "Grand Teton / footprints 7711-7712 of 8354")
	)
	(layers
		(0 "F.Cu" signal "TOP")
		(4 "In1.Cu" signal "GND")
		(6 "In2.Cu" signal "IN1")
		(8 "In3.Cu" signal "GND1")
		(10 "In4.Cu" signal "IN2")
		(12 "In5.Cu" signal "GND2")
		(14 "In6.Cu" signal "IN3")
		(16 "In7.Cu" signal "GND3")
		(18 "In8.Cu" signal "VCC")
		(20 "In9.Cu" signal "VCC1")
		(22 "In10.Cu" signal "GND4")
		(24 "In11.Cu" signal "IN4")
		(26 "In12.Cu" signal "GND5")
		(28 "In13.Cu" signal "IN5")
		(30 "In14.Cu" signal "GND6")
		(32 "In15.Cu" signal "IN6")
		(34 "In16.Cu" signal "GND7")
		(2 "B.Cu" signal "BOTTOM")
		(9 "F.Adhes" user "F.Adhesive")
		(11 "B.Adhes" user "B.Adhesive")
		(13 "F.Paste" user "Package Geometry/Pastemask Top")
		(15 "B.Paste" user "Package Geometry/Pastemask Bottom")
		(5 "F.SilkS" user "Ref Des/Silkscreen Top")
		(7 "B.SilkS" user "Ref Des/Silkscreen Bottom")
		(1 "F.Mask" user "Board Geometry/Soldermask Top")
		(3 "B.Mask" user "Board Geometry/Soldermask Bottom")
		(17 "Dwgs.User" user "User.Drawings")
		(19 "Cmts.User" user "User.Comments")
		(21 "Eco1.User" user "User.Eco1")
		(23 "Eco2.User" user "User.Eco2")
		(25 "Edge.Cuts" user "Board Geometry/Outline")
		(27 "Margin" user)
		(31 "F.CrtYd" user "Package Geometry/Place Bound Top")
		(29 "B.CrtYd" user "Package Geometry/Place Bound Bottom")
		(35 "F.Fab" user "Ref Des/Assembly Top")
		(33 "B.Fab" user "Ref Des/Assembly Bottom")
	)
	(footprint ""
		(layer "B.Cu")
		(at 140.168376 -386.745988 -90)
		(property "Reference" "C436"
			(at 0 0 90)
			(layer "B.SilkS")
			(hide yes)
			(effects
				(font
					(size 1.27 1.27)
				)
				(justify mirror)
			)
		)
		(property "Value" ""
			(at 0 0 90)
			(layer "B.Fab")
			(effects
				(font
					(size 1.27 1.27)
				)
				(justify mirror)
			)
		)
		(duplicate_pad_numbers_are_jumpers no)
		(fp_line
			(start -0.7874 0.4064)
			(end 0.7874 0.4064)
			(stroke
				(width 0.1524)
				(type default)
			)
			(layer "B.SilkS")
		)
		(fp_line
			(start 0.7874 0.4064)
			(end 0.7874 -0.4064)
			(stroke
				(width 0.1524)
				(type default)
			)
			(layer "B.SilkS")
		)
		(fp_line
			(start -0.7874 -0.4064)
			(end -0.7874 0.4064)
			(stroke
				(width 0.1524)
				(type default)
			)
			(layer "B.SilkS")
		)
		(fp_line
			(start 0.7874 -0.4064)
			(end -0.7874 -0.4064)
			(stroke
				(width 0.1524)
				(type default)
			)
			(layer "B.SilkS")
		)
		(fp_line
			(start -0.67945 0.3048)
			(end -0.120396 0.3048)
			(stroke
				(width 0.1)
				(type default)
			)
			(layer "B.Fab")
		)
		(fp_line
			(start -0.120396 0.3048)
			(end -0.120396 0.2794)
			(stroke
				(width 0.1)
				(type default)
			)
			(layer "B.Fab")
		)
		(fp_line
			(start 0.12065 0.3048)
			(end 0.67945 0.3048)
			(stroke
				(width 0.1)
				(type default)
			)
			(layer "B.Fab")
		)
		(fp_line
			(start 0.67945 0.3048)
			(end 0.67945 -0.305054)
			(stroke
				(width 0.1)
				(type default)
			)
			(layer "B.Fab")
		)
		(fp_line
			(start -0.120396 0.2794)
			(end 0.12065 0.2794)
			(stroke
				(width 0.1)
				(type default)
			)
			(layer "B.Fab")
		)
		(fp_line
			(start 0.12065 0.2794)
			(end 0.12065 0.3048)
			(stroke
				(width 0.1)
				(type default)
			)
			(layer "B.Fab")
		)
		(fp_line
			(start -0.12065 -0.2794)
			(end -0.12065 -0.3048)
			(stroke
				(width 0.1)
				(type default)
			)
			(layer "B.Fab")
		)
		(fp_line
			(start 0.12065 -0.2794)
			(end -0.12065 -0.2794)
			(stroke
				(width 0.1)
				(type default)
			)
			(layer "B.Fab")
		)
		(fp_line
			(start -0.67945 -0.3048)
			(end -0.67945 0.3048)
			(stroke
				(width 0.1)
				(type default)
			)
			(layer "B.Fab")
		)
		(fp_line
			(start -0.12065 -0.3048)
			(end -0.67945 -0.3048)
			(stroke
				(width 0.1)
				(type default)
			)
			(layer "B.Fab")
		)
		(fp_line
			(start 0.12065 -0.305054)
			(end 0.12065 -0.2794)
			(stroke
				(width 0.1)
				(type default)
			)
			(layer "B.Fab")
		)
		(fp_line
			(start 0.67945 -0.305054)
			(end 0.12065 -0.305054)
			(stroke
				(width 0.1)
				(type default)
			)
			(layer "B.Fab")
		)
		(pad "1" smd circle
			(at 0.40005 0 90)
			(size 0 0)
			(layers "B.Cu" "B.Mask" "B.Paste")
			(net "P1V8_CPU1_RT_1D")
		)
		(pad "2" smd circle
			(at -0.40005 0 90)
			(size 0 0)
			(layers "B.Cu" "B.Mask" "B.Paste")
			(net "GND")
		)
	)
	(footprint ""
		(layer "B.Cu")
		(at 358.216454 -267.52931)
		(property "Reference" "C2240"
			(at 0 0 0)
			(layer "B.SilkS")
			(hide yes)
			(effects
				(font
					(size 1.27 1.27)
				)
				(justify mirror)
			)
		)
		(property "Value" ""
			(at 0 0 0)
			(layer "B.Fab")
			(effects
				(font
					(size 1.27 1.27)
				)
				(justify mirror)
			)
		)
		(duplicate_pad_numbers_are_jumpers no)
		(fp_line
			(start -0.7874 -0.4064)
			(end -0.7874 0.4064)
			(stroke
				(width 0.1524)
				(type default)
			)
			(layer "B.SilkS")
		)
		(fp_line
			(start -0.7874 0.4064)
			(end 0.7874 0.4064)
			(stroke
				(width 0.1524)
				(type default)
			)
			(layer "B.SilkS")
		)
		(fp_line
			(start 0.7874 -0.4064)
			(end -0.7874 -0.4064)
			(stroke
				(width 0.1524)
				(type default)
			)
			(layer "B.SilkS")
		)
		(fp_line
			(start 0.7874 0.4064)
			(end 0.7874 -0.4064)
			(stroke
				(width 0.1524)
				(type default)
			)
			(layer "B.SilkS")
		)
		(fp_line
			(start -0.67945 -0.3048)
			(end -0.67945 0.3048)
			(stroke
				(width 0.1)
				(type default)
			)
			(layer "B.Fab")
		)
		(fp_line
			(start -0.67945 0.3048)
			(end -0.120396 0.3048)
			(stroke
				(width 0.1)
				(type default)
			)
			(layer "B.Fab")
		)
		(fp_line
			(start -0.12065 -0.3048)
			(end -0.67945 -0.3048)
			(stroke
				(width 0.1)
				(type default)
			)
			(layer "B.Fab")
		)
		(fp_line
			(start -0.12065 -0.2794)
			(end -0.12065 -0.3048)
			(stroke
				(width 0.1)
				(type default)
			)
			(layer "B.Fab")
		)
		(fp_line
			(start -0.120396 0.2794)
			(end 0.12065 0.2794)
			(stroke
				(width 0.1)
				(type default)
			)
			(layer "B.Fab")
		)
		(fp_line
			(start -0.120396 0.3048)
			(end -0.120396 0.2794)
			(stroke
				(width 0.1)
				(type default)
			)
			(layer "B.Fab")
		)
		(fp_line
			(start 0.12065 -0.305054)
			(end 0.12065 -0.2794)
			(stroke
				(width 0.1)
				(type default)
			)
			(layer "B.Fab")
		)
		(fp_line
			(start 0.12065 -0.2794)
			(end -0.12065 -0.2794)
			(stroke
				(width 0.1)
				(type default)
			)
			(layer "B.Fab")
		)
		(fp_line
			(start 0.12065 0.2794)
			(end 0.12065 0.3048)
			(stroke
				(width 0.1)
				(type default)
			)
			(layer "B.Fab")
		)
		(fp_line
			(start 0.12065 0.3048)
			(end 0.67945 0.3048)
			(stroke
				(width 0.1)
				(type default)
			)
			(layer "B.Fab")
		)
		(fp_line
			(start 0.67945 -0.305054)
			(end 0.12065 -0.305054)
			(stroke
				(width 0.1)
				(type default)
			)
			(layer "B.Fab")
		)
		(fp_line
			(start 0.67945 0.3048)
			(end 0.67945 -0.305054)
			(stroke
				(width 0.1)
				(type default)
			)
			(layer "B.Fab")
		)
		(pad "1" smd circle
			(at 0.40005 0 180)
			(size 0 0)
			(layers "B.Cu" "B.Mask" "B.Paste")
			(net "PVDDCR_CPU1_P0")
		)
		(pad "2" smd circle
			(at -0.40005 0 180)
			(size 0 0)
			(layers "B.Cu" "B.Mask" "B.Paste")
			(net "GND")
		)
	)
)
